FILE_TYPE=LIBRARY_PARTS;
TIME=' Created/Modified on Thu Jun 22 13:52:55 2006' ;
primitive 'HOLE';
  pin
    '1':
      PIN_NUMBER='(1)';
      INPUT_LOAD='(-0.01,0.01)';
      OUTPUT_LOAD='(1.0,-1.0)';
      BIDIRECTIONAL='TRUE';
  end_pin;
  body
    CLASS='DISCRETE';
    PART_NAME='HOLE';
    PHYS_DES_PREFIX='H';
  end_body;
end_primitive;
END.
